(kicad_pcb
	(version 20260206)
	(generator "pcbnew")
	(generator_version "10.0")
	(general
		(thickness 1.6)
		(legacy_teardrops no)
	)
	(paper "A4")
	(title_block
		(title "Wiwynn_Tioga_Pass_MB.brd")
		(comment 1 "Tioga Pass / footprints 1042-1048 of 4770")
	)
	(layers
		(0 "F.Cu" signal "TOP")
		(4 "In1.Cu" signal "L2GND")
		(6 "In2.Cu" signal "L3")
		(8 "In3.Cu" signal "L4GND")
		(10 "In4.Cu" signal "L5")
		(12 "In5.Cu" signal "L6GND")
		(14 "In6.Cu" signal "L7VCC")
		(16 "In7.Cu" signal "L8VCC")
		(18 "In8.Cu" signal "L9GND")
		(20 "In9.Cu" signal "L10")
		(22 "In10.Cu" signal "L11GND")
		(24 "In11.Cu" signal "L12")
		(26 "In12.Cu" signal "L13GND")
		(2 "B.Cu" signal "BOTTOM")
		(9 "F.Adhes" user "F.Adhesive")
		(11 "B.Adhes" user "B.Adhesive")
		(13 "F.Paste" user "Package Geometry/Pastemask Top")
		(15 "B.Paste" user "Package Geometry/Pastemask Bottom")
		(5 "F.SilkS" user "Ref Des/Silkscreen Top")
		(7 "B.SilkS" user "Ref Des/Silkscreen Bottom")
		(1 "F.Mask" user "Board Geometry/Soldermask Top")
		(3 "B.Mask" user "Board Geometry/Soldermask Bottom")
		(17 "Dwgs.User" user "User.Drawings")
		(19 "Cmts.User" user "User.Comments")
		(21 "Eco1.User" user "User.Eco1")
		(23 "Eco2.User" user "User.Eco2")
		(25 "Edge.Cuts" user "Board Geometry/Outline")
		(27 "Margin" user)
		(31 "F.CrtYd" user "Package Geometry/Place Bound Top")
		(29 "B.CrtYd" user "Package Geometry/Place Bound Bottom")
		(35 "F.Fab" user "Ref Des/Assembly Top")
		(33 "B.Fab" user "Ref Des/Assembly Bottom")
	)
	(footprint ""
		(layer "F.Cu")
		(at 411.327092 -125.088904 -90)
		(property "Reference" "R8B12"
			(at 0 0 270)
			(layer "F.SilkS")
			(hide yes)
			(effects
				(font
					(size 1.27 1.27)
				)
			)
		)
		(property "Value" ""
			(at 0 0 270)
			(layer "F.Fab")
			(effects
				(font
					(size 1.27 1.27)
				)
			)
		)
		(duplicate_pad_numbers_are_jumpers no)
		(fp_poly
			(pts
				(xy -0.2794 -0.1016) (xy 0.2794 -0.1016) (xy 0.2794 0.9906) (xy -0.2794 0.9906)
			)
			(stroke
				(width 0)
				(type default)
			)
			(fill no)
			(layer "F.CrtYd")
		)
		(fp_line
			(start -0.2794 0.9906)
			(end 0.2794 0.9906)
			(stroke
				(width 0.1)
				(type default)
			)
			(layer "F.Fab")
		)
		(fp_line
			(start 0.2794 0.9906)
			(end 0.2794 -0.1016)
			(stroke
				(width 0.1)
				(type default)
			)
			(layer "F.Fab")
		)
		(fp_line
			(start -0.2794 -0.1016)
			(end -0.2794 0.9906)
			(stroke
				(width 0.1)
				(type default)
			)
			(layer "F.Fab")
		)
		(fp_line
			(start 0.2794 -0.1016)
			(end -0.2794 -0.1016)
			(stroke
				(width 0.1)
				(type default)
			)
			(layer "F.Fab")
		)
		(pad "1" smd rect
			(at 0 0 270)
			(size 0.508 0.508)
			(layers "F.Cu" "F.Mask" "F.Paste")
			(net "VSENSE_P1V05_PCH_STBY_AVSN")
		)
		(pad "2" smd rect
			(at 0 0.889 270)
			(size 0.508 0.508)
			(layers "F.Cu" "F.Mask" "F.Paste")
			(net "GND")
		)
		(zone
			(layer "F.Cu")
			(hatch none 0.5)
			(connect_pads
				(clearance 0)
			)
			(min_thickness 0.25)
			(keepout
				(tracks not_allowed)
				(vias allowed)
				(pads allowed)
				(copperpour not_allowed)
				(footprints allowed)
			)
			(placement
				(enabled no)
				(sheetname "")
			)
			(fill
				(thermal_gap 0.5)
				(thermal_bridge_width 0.5)
				(island_removal_mode 0)
			)
			(polygon
				(pts
					(xy 410.692092 -125.342904) (xy 410.692092 -124.834904) (xy 411.073092 -124.834904) (xy 411.073092 -125.342904)
				)
			)
		)
		(zone
			(layer "F.Cu")
			(hatch none 0.5)
			(connect_pads
				(clearance 0)
			)
			(min_thickness 0.25)
			(keepout
				(tracks allowed)
				(vias not_allowed)
				(pads allowed)
				(copperpour not_allowed)
				(footprints allowed)
			)
			(placement
				(enabled no)
				(sheetname "")
			)
			(fill
				(thermal_gap 0.5)
				(thermal_bridge_width 0.5)
				(island_removal_mode 0)
			)
			(polygon
				(pts
					(xy 411.073092 -125.342904) (xy 411.073092 -124.834904) (xy 410.692092 -124.834904) (xy 410.692092 -125.342904)
				)
			)
		)
	)
	(footprint ""
		(layer "F.Cu")
		(at 395.732 -0.2286)
		(property "Reference" "R8G17"
			(at 0 0 0)
			(layer "F.SilkS")
			(hide yes)
			(effects
				(font
					(size 1.27 1.27)
				)
			)
		)
		(property "Value" ""
			(at 0 0 0)
			(layer "F.Fab")
			(effects
				(font
					(size 1.27 1.27)
				)
			)
		)
		(duplicate_pad_numbers_are_jumpers no)
		(fp_poly
			(pts
				(xy -0.2794 -0.1016) (xy 0.2794 -0.1016) (xy 0.2794 0.9906) (xy -0.2794 0.9906)
			)
			(stroke
				(width 0)
				(type default)
			)
			(fill no)
			(layer "F.CrtYd")
		)
		(fp_line
			(start -0.2794 -0.1016)
			(end -0.2794 0.9906)
			(stroke
				(width 0.1)
				(type default)
			)
			(layer "F.Fab")
		)
		(fp_line
			(start -0.2794 0.9906)
			(end 0.2794 0.9906)
			(stroke
				(width 0.1)
				(type default)
			)
			(layer "F.Fab")
		)
		(fp_line
			(start 0.2794 -0.1016)
			(end -0.2794 -0.1016)
			(stroke
				(width 0.1)
				(type default)
			)
			(layer "F.Fab")
		)
		(fp_line
			(start 0.2794 0.9906)
			(end 0.2794 -0.1016)
			(stroke
				(width 0.1)
				(type default)
			)
			(layer "F.Fab")
		)
		(pad "1" smd rect
			(at 0 0)
			(size 0.508 0.508)
			(layers "F.Cu" "F.Mask" "F.Paste")
			(net "JTAG_BMC_TCK")
		)
		(pad "2" smd rect
			(at 0 0.889)
			(size 0.508 0.508)
			(layers "F.Cu" "F.Mask" "F.Paste")
			(net "JTAG_TCK")
		)
		(zone
			(layer "F.Cu")
			(hatch none 0.5)
			(connect_pads
				(clearance 0)
			)
			(min_thickness 0.25)
			(keepout
				(tracks allowed)
				(vias not_allowed)
				(pads allowed)
				(copperpour not_allowed)
				(footprints allowed)
			)
			(placement
				(enabled no)
				(sheetname "")
			)
			(fill
				(thermal_gap 0.5)
				(thermal_bridge_width 0.5)
				(island_removal_mode 0)
			)
			(polygon
				(pts
					(xy 395.478 0.0254) (xy 395.986 0.0254) (xy 395.986 0.4064) (xy 395.478 0.4064)
				)
			)
		)
		(zone
			(layer "F.Cu")
			(hatch none 0.5)
			(connect_pads
				(clearance 0)
			)
			(min_thickness 0.25)
			(keepout
				(tracks not_allowed)
				(vias allowed)
				(pads allowed)
				(copperpour not_allowed)
				(footprints allowed)
			)
			(placement
				(enabled no)
				(sheetname "")
			)
			(fill
				(thermal_gap 0.5)
				(thermal_bridge_width 0.5)
				(island_removal_mode 0)
			)
			(polygon
				(pts
					(xy 395.478 0.4064) (xy 395.986 0.4064) (xy 395.986 0.0254) (xy 395.478 0.0254)
				)
			)
		)
	)
	(footprint ""
		(layer "F.Cu")
		(at 14.097 -83.058 90)
		(property "Reference" "R1D15"
			(at 0 0 90)
			(layer "F.SilkS")
			(hide yes)
			(effects
				(font
					(size 1.27 1.27)
				)
			)
		)
		(property "Value" ""
			(at 0 0 90)
			(layer "F.Fab")
			(effects
				(font
					(size 1.27 1.27)
				)
			)
		)
		(duplicate_pad_numbers_are_jumpers no)
		(fp_poly
			(pts
				(xy -0.2794 -0.1016) (xy 0.2794 -0.1016) (xy 0.2794 0.9906) (xy -0.2794 0.9906)
			)
			(stroke
				(width 0)
				(type default)
			)
			(fill no)
			(layer "F.CrtYd")
		)
		(fp_line
			(start 0.2794 -0.1016)
			(end -0.2794 -0.1016)
			(stroke
				(width 0.1)
				(type default)
			)
			(layer "F.Fab")
		)
		(fp_line
			(start -0.2794 -0.1016)
			(end -0.2794 0.9906)
			(stroke
				(width 0.1)
				(type default)
			)
			(layer "F.Fab")
		)
		(fp_line
			(start 0.2794 0.9906)
			(end 0.2794 -0.1016)
			(stroke
				(width 0.1)
				(type default)
			)
			(layer "F.Fab")
		)
		(fp_line
			(start -0.2794 0.9906)
			(end 0.2794 0.9906)
			(stroke
				(width 0.1)
				(type default)
			)
			(layer "F.Fab")
		)
		(pad "1" smd rect
			(at 0 0 90)
			(size 0.508 0.508)
			(layers "F.Cu" "F.Mask" "F.Paste")
			(net "P12V_PSU")
		)
		(pad "2" smd rect
			(at 0 0.889 90)
			(size 0.508 0.508)
			(layers "F.Cu" "F.Mask" "F.Paste")
			(net "A_HSC_OCP_SEL")
		)
		(zone
			(layer "F.Cu")
			(hatch none 0.5)
			(connect_pads
				(clearance 0)
			)
			(min_thickness 0.25)
			(keepout
				(tracks allowed)
				(vias not_allowed)
				(pads allowed)
				(copperpour not_allowed)
				(footprints allowed)
			)
			(placement
				(enabled no)
				(sheetname "")
			)
			(fill
				(thermal_gap 0.5)
				(thermal_bridge_width 0.5)
				(island_removal_mode 0)
			)
			(polygon
				(pts
					(xy 14.351 -82.804) (xy 14.351 -83.312) (xy 14.732 -83.312) (xy 14.732 -82.804)
				)
			)
		)
		(zone
			(layer "F.Cu")
			(hatch none 0.5)
			(connect_pads
				(clearance 0)
			)
			(min_thickness 0.25)
			(keepout
				(tracks not_allowed)
				(vias allowed)
				(pads allowed)
				(copperpour not_allowed)
				(footprints allowed)
			)
			(placement
				(enabled no)
				(sheetname "")
			)
			(fill
				(thermal_gap 0.5)
				(thermal_bridge_width 0.5)
				(island_removal_mode 0)
			)
			(polygon
				(pts
					(xy 14.732 -82.804) (xy 14.732 -83.312) (xy 14.351 -83.312) (xy 14.351 -82.804)
				)
			)
		)
	)
	(footprint ""
		(layer "F.Cu")
		(at 248.8565 -3.3528 -90)
		(property "Reference" "C5G12"
			(at 1.848866 0.752348 270)
			(unlocked yes)
			(layer "F.SilkS")
			(effects
				(font
					(size 1.27 0.9652)
					(thickness 0.1524)
				)
			)
		)
		(property "Value" ""
			(at 0 0 270)
			(layer "F.Fab")
			(effects
				(font
					(size 1.27 1.27)
				)
			)
		)
		(duplicate_pad_numbers_are_jumpers no)
		(fp_rect
			(start -0.500126 1.598422)
			(end 0.500126 -0.201422)
			(stroke
				(width 0)
				(type default)
			)
			(fill no)
			(layer "F.CrtYd")
		)
		(fp_line
			(start -0.500126 1.598422)
			(end -0.500126 -0.201422)
			(stroke
				(width 0.1)
				(type default)
			)
			(layer "F.Fab")
		)
		(fp_line
			(start 0.500126 1.598422)
			(end -0.500126 1.598422)
			(stroke
				(width 0.1)
				(type default)
			)
			(layer "F.Fab")
		)
		(fp_line
			(start -0.500126 -0.201422)
			(end 0.500126 -0.201422)
			(stroke
				(width 0.1)
				(type default)
			)
			(layer "F.Fab")
		)
		(fp_line
			(start 0.500126 -0.201422)
			(end 0.500126 1.598422)
			(stroke
				(width 0.1)
				(type default)
			)
			(layer "F.Fab")
		)
		(pad "1" smd rect
			(at 0 0 180)
			(size 0.889 0.9906)
			(layers "F.Cu" "F.Mask" "F.Paste")
			(net "PVDDQ_ABC")
		)
		(pad "2" smd rect
			(at 0 1.397 180)
			(size 0.889 0.9906)
			(layers "F.Cu" "F.Mask" "F.Paste")
			(net "GND")
		)
		(zone
			(layer "F.Cu")
			(hatch none 0.5)
			(connect_pads
				(clearance 0)
			)
			(min_thickness 0.25)
			(keepout
				(tracks not_allowed)
				(vias allowed)
				(pads allowed)
				(copperpour not_allowed)
				(footprints allowed)
			)
			(placement
				(enabled no)
				(sheetname "")
			)
			(fill
				(thermal_gap 0.5)
				(thermal_bridge_width 0.5)
				(island_removal_mode 0)
			)
			(polygon
				(pts
					(xy 247.904 -3.8481) (xy 247.904 -2.8575) (xy 248.412 -2.8575) (xy 248.412 -3.8481)
				)
			)
		)
		(zone
			(layer "F.Cu")
			(hatch none 0.5)
			(connect_pads
				(clearance 0)
			)
			(min_thickness 0.25)
			(keepout
				(tracks allowed)
				(vias not_allowed)
				(pads allowed)
				(copperpour not_allowed)
				(footprints allowed)
			)
			(placement
				(enabled no)
				(sheetname "")
			)
			(fill
				(thermal_gap 0.5)
				(thermal_bridge_width 0.5)
				(island_removal_mode 0)
			)
			(polygon
				(pts
					(xy 247.904 -3.8481) (xy 247.904 -2.8575) (xy 248.412 -2.8575) (xy 248.412 -3.8481)
				)
			)
		)
	)
	(footprint ""
		(layer "F.Cu")
		(at 0.724662 -124.076968 90)
		(property "Reference" "RF22"
			(at -0.8382 -0.67818 90)
			(unlocked yes)
			(layer "F.SilkS")
			(effects
				(font
					(size 0.4064 0.254)
					(thickness 0.1524)
				)
				(justify left)
			)
		)
		(property "Value" ""
			(at 0 0 90)
			(layer "F.Fab")
			(effects
				(font
					(size 1.27 1.27)
				)
			)
		)
		(duplicate_pad_numbers_are_jumpers no)
		(fp_poly
			(pts
				(xy -0.2794 -0.1016) (xy 0.2794 -0.1016) (xy 0.2794 0.9906) (xy -0.2794 0.9906)
			)
			(stroke
				(width 0)
				(type default)
			)
			(fill no)
			(layer "F.CrtYd")
		)
		(fp_line
			(start 0.2794 -0.1016)
			(end -0.2794 -0.1016)
			(stroke
				(width 0.1)
				(type default)
			)
			(layer "F.Fab")
		)
		(fp_line
			(start -0.2794 -0.1016)
			(end -0.2794 0.9906)
			(stroke
				(width 0.1)
				(type default)
			)
			(layer "F.Fab")
		)
		(fp_line
			(start 0.2794 0.9906)
			(end 0.2794 -0.1016)
			(stroke
				(width 0.1)
				(type default)
			)
			(layer "F.Fab")
		)
		(fp_line
			(start -0.2794 0.9906)
			(end 0.2794 0.9906)
			(stroke
				(width 0.1)
				(type default)
			)
			(layer "F.Fab")
		)
		(pad "1" smd rect
			(at 0 0 90)
			(size 0.508 0.508)
			(layers "F.Cu" "F.Mask" "F.Paste")
			(net "VR_PVDDQ_KLM_AIREF2")
		)
		(pad "2" smd rect
			(at 0 0.889 90)
			(size 0.508 0.508)
			(layers "F.Cu" "F.Mask" "F.Paste")
			(net "ISENSE_PVDDQ_KLM_PH2_IMON")
		)
		(zone
			(layer "F.Cu")
			(hatch none 0.5)
			(connect_pads
				(clearance 0)
			)
			(min_thickness 0.25)
			(keepout
				(tracks allowed)
				(vias not_allowed)
				(pads allowed)
				(copperpour not_allowed)
				(footprints allowed)
			)
			(placement
				(enabled no)
				(sheetname "")
			)
			(fill
				(thermal_gap 0.5)
				(thermal_bridge_width 0.5)
				(island_removal_mode 0)
			)
			(polygon
				(pts
					(xy 0.978662 -123.822968) (xy 0.978662 -124.330968) (xy 1.359662 -124.330968) (xy 1.359662 -123.822968)
				)
			)
		)
		(zone
			(layer "F.Cu")
			(hatch none 0.5)
			(connect_pads
				(clearance 0)
			)
			(min_thickness 0.25)
			(keepout
				(tracks not_allowed)
				(vias allowed)
				(pads allowed)
				(copperpour not_allowed)
				(footprints allowed)
			)
			(placement
				(enabled no)
				(sheetname "")
			)
			(fill
				(thermal_gap 0.5)
				(thermal_bridge_width 0.5)
				(island_removal_mode 0)
			)
			(polygon
				(pts
					(xy 1.359662 -123.822968) (xy 1.359662 -124.330968) (xy 0.978662 -124.330968) (xy 0.978662 -123.822968)
				)
			)
		)
	)
	(footprint ""
		(layer "F.Cu")
		(at 376.678444 -10.916158)
		(property "Reference" "C7G17"
			(at 0 0 0)
			(layer "F.SilkS")
			(hide yes)
			(effects
				(font
					(size 1.27 1.27)
				)
			)
		)
		(property "Value" ""
			(at 0 0 0)
			(layer "F.Fab")
			(effects
				(font
					(size 1.27 1.27)
				)
			)
		)
		(duplicate_pad_numbers_are_jumpers no)
		(fp_rect
			(start -0.3048 0.9906)
			(end 0.3048 -0.1016)
			(stroke
				(width 0)
				(type default)
			)
			(fill no)
			(layer "F.CrtYd")
		)
		(fp_line
			(start -0.3048 -0.1016)
			(end -0.3048 0.9906)
			(stroke
				(width 0.1)
				(type default)
			)
			(layer "F.Fab")
		)
		(fp_line
			(start -0.3048 0.9906)
			(end 0.3048 0.9906)
			(stroke
				(width 0.1)
				(type default)
			)
			(layer "F.Fab")
		)
		(fp_line
			(start 0.3048 -0.1016)
			(end -0.3048 -0.1016)
			(stroke
				(width 0.1)
				(type default)
			)
			(layer "F.Fab")
		)
		(fp_line
			(start 0.3048 0.9906)
			(end 0.3048 -0.1016)
			(stroke
				(width 0.1)
				(type default)
			)
			(layer "F.Fab")
		)
		(pad "1" smd rect
			(at 0 0)
			(size 0.508 0.508)
			(layers "F.Cu" "F.Mask" "F.Paste")
			(net "P3E_CPU0_PE2_SS_TXP<9>")
		)
		(pad "2" smd rect
			(at 0 0.889)
			(size 0.508 0.508)
			(layers "F.Cu" "F.Mask" "F.Paste")
			(net "P3E_CPU0_PE2_SS_C_TXP<9>")
		)
		(zone
			(layer "F.Cu")
			(hatch none 0.5)
			(connect_pads
				(clearance 0)
			)
			(min_thickness 0.25)
			(keepout
				(tracks not_allowed)
				(vias allowed)
				(pads allowed)
				(copperpour not_allowed)
				(footprints allowed)
			)
			(placement
				(enabled no)
				(sheetname "")
			)
			(fill
				(thermal_gap 0.5)
				(thermal_bridge_width 0.5)
				(island_removal_mode 0)
			)
			(polygon
				(pts
					(xy 376.424444 -10.281158) (xy 376.932444 -10.281158) (xy 376.932444 -10.662158) (xy 376.424444 -10.662158)
				)
			)
		)
		(zone
			(layer "F.Cu")
			(hatch none 0.5)
			(connect_pads
				(clearance 0)
			)
			(min_thickness 0.25)
			(keepout
				(tracks allowed)
				(vias not_allowed)
				(pads allowed)
				(copperpour not_allowed)
				(footprints allowed)
			)
			(placement
				(enabled no)
				(sheetname "")
			)
			(fill
				(thermal_gap 0.5)
				(thermal_bridge_width 0.5)
				(island_removal_mode 0)
			)
			(polygon
				(pts
					(xy 376.424444 -10.281158) (xy 376.932444 -10.281158) (xy 376.932444 -10.662158) (xy 376.424444 -10.662158)
				)
			)
		)
	)
	(footprint ""
		(layer "F.Cu")
		(at 180.848 -8.255)
		(property "Reference" "R4G12"
			(at 0 0 0)
			(layer "F.SilkS")
			(hide yes)
			(effects
				(font
					(size 1.27 1.27)
				)
			)
		)
		(property "Value" ""
			(at 0 0 0)
			(layer "F.Fab")
			(effects
				(font
					(size 1.27 1.27)
				)
			)
		)
		(duplicate_pad_numbers_are_jumpers no)
		(fp_poly
			(pts
				(xy -0.2794 -0.1016) (xy 0.2794 -0.1016) (xy 0.2794 0.9906) (xy -0.2794 0.9906)
			)
			(stroke
				(width 0)
				(type default)
			)
			(fill no)
			(layer "F.CrtYd")
		)
		(fp_line
			(start -0.2794 -0.1016)
			(end -0.2794 0.9906)
			(stroke
				(width 0.1)
				(type default)
			)
			(layer "F.Fab")
		)
		(fp_line
			(start -0.2794 0.9906)
			(end 0.2794 0.9906)
			(stroke
				(width 0.1)
				(type default)
			)
			(layer "F.Fab")
		)
		(fp_line
			(start 0.2794 -0.1016)
			(end -0.2794 -0.1016)
			(stroke
				(width 0.1)
				(type default)
			)
			(layer "F.Fab")
		)
		(fp_line
			(start 0.2794 0.9906)
			(end 0.2794 -0.1016)
			(stroke
				(width 0.1)
				(type default)
			)
			(layer "F.Fab")
		)
		(pad "1" smd rect
			(at 0 0)
			(size 0.508 0.508)
			(layers "F.Cu" "F.Mask" "F.Paste")
			(net "PWRGD_PVPP_GHJ_R")
		)
		(pad "2" smd rect
			(at 0 0.889)
			(size 0.508 0.508)
			(layers "F.Cu" "F.Mask" "F.Paste")
			(net "PWRGD_PVPP_GHJ")
		)
		(zone
			(layer "F.Cu")
			(hatch none 0.5)
			(connect_pads
				(clearance 0)
			)
			(min_thickness 0.25)
			(keepout
				(tracks allowed)
				(vias not_allowed)
				(pads allowed)
				(copperpour not_allowed)
				(footprints allowed)
			)
			(placement
				(enabled no)
				(sheetname "")
			)
			(fill
				(thermal_gap 0.5)
				(thermal_bridge_width 0.5)
				(island_removal_mode 0)
			)
			(polygon
				(pts
					(xy 180.594 -8.001) (xy 181.102 -8.001) (xy 181.102 -7.62) (xy 180.594 -7.62)
				)
			)
		)
		(zone
			(layer "F.Cu")
			(hatch none 0.5)
			(connect_pads
				(clearance 0)
			)
			(min_thickness 0.25)
			(keepout
				(tracks not_allowed)
				(vias allowed)
				(pads allowed)
				(copperpour not_allowed)
				(footprints allowed)
			)
			(placement
				(enabled no)
				(sheetname "")
			)
			(fill
				(thermal_gap 0.5)
				(thermal_bridge_width 0.5)
				(island_removal_mode 0)
			)
			(polygon
				(pts
					(xy 180.594 -7.62) (xy 181.102 -7.62) (xy 181.102 -8.001) (xy 180.594 -8.001)
				)
			)
		)
	)
)
